FILE_TYPE = MACRO_DRAWING;
SET COLOR_WIRE YELLOW;
SET COLOR_PROP MONO;
SET COLOR_DOT WHITE;
SET COLOR_ARC YELLOW;
SET COLOR_BODY GREEN;
SET COLOR_NOTE MONO;
SET PROP_DISPLAY VALUE;
SET PAGE_NUMBER P35;
FORCEADD GND..1
(-5975 1400);
FORCEPROP 3 LASTPIN (-5975 1450) SIG_NAME GND\g
J 0
(-5965 1460);
DISPLAY 0.659574 (-5965 1460);
PAINT MONO (-5965 1460);
DISPLAY INVISIBLE (-5965 1460);
FORCEPROP 1 LAST VOLTAGE 0.0V
J 0
(-6020 1357);
DISPLAY 0.340426 (-6020 1357);
PAINT SKYBLUE (-6020 1357);
DISPLAY INVISIBLE (-6020 1357);
FORCEPROP 2 LAST CDS_LIB mstr_symbols
J 0
(-5975 1400);
PAINT MONO (-5975 1400);
DISPLAY INVISIBLE (-5975 1400);
FORCEPROP 1 LAST SIZE 1B
J 0
(-5900 1350);
DISPLAY 1.170213 (-5900 1350);
PAINT AQUA (-5900 1350);
DISPLAY INVISIBLE (-5900 1350);
FORCEPROP 1 LAST BODY_TYPE PLUMBING
J 0
(-6020 1357);
DISPLAY 0.340426 (-6020 1357);
PAINT GREEN (-6020 1357);
DISPLAY INVISIBLE (-6020 1357);
FORCEPROP 1 LAST PATH I2
J 0
(-5900 1400);
DISPLAY 0.872340 (-5900 1400);
PAINT AQUA (-5900 1400);
DISPLAY INVISIBLE (-5900 1400);
FORCEPROP 1 LAST HDL_POWER GND
J 0
(-5975 1550);
DISPLAY 1.170213 (-5975 1550);
PAINT GREEN (-5975 1550);
DISPLAY INVISIBLE (-5975 1550);
FORCEADD SKX_EXT_B..15
(-4225 2625);
FORCEPROP 1 LAST LOCATION U5D1
J 0
(-4975 3875);
DISPLAY 0.617021 (-4975 3875);
PAINT AQUA (-4975 3875);
FORCEPROP 1 LAST PART_NUMBER TBD
J 0
(-4975 1425);
DISPLAY 0.617021 (-4975 1425);
PAINT BLUE (-4975 1425);
FORCEPROP 1 LAST MATERIAL IC
J 0
(-4975 3825);
DISPLAY 0.617021 (-4975 3825);
PAINT SKYBLUE (-4975 3825);
FORCEPROP 2 LASTPIN (-3425 3625) $PN CA12
J 0
(-3415 3635);
DISPLAY 0.617021 (-3415 3635);
PAINT ORANGE (-3415 3635);
FORCEPROP 2 LASTPIN (-3425 3575) $PN CB11
J 0
(-3415 3585);
DISPLAY 0.617021 (-3415 3585);
PAINT ORANGE (-3415 3585);
FORCEPROP 2 LASTPIN (-3425 3525) $PN CD11
J 0
(-3415 3535);
DISPLAY 0.617021 (-3415 3535);
PAINT ORANGE (-3415 3535);
FORCEPROP 2 LASTPIN (-3425 3475) $PN CF11
J 0
(-3415 3485);
DISPLAY 0.617021 (-3415 3485);
PAINT ORANGE (-3415 3485);
FORCEPROP 2 LASTPIN (-3425 3425) $PN CG12
J 0
(-3415 3435);
DISPLAY 0.617021 (-3415 3435);
PAINT ORANGE (-3415 3435);
FORCEPROP 2 LASTPIN (-3425 3375) $PN CH13
J 0
(-3415 3385);
DISPLAY 0.617021 (-3415 3385);
PAINT ORANGE (-3415 3385);
FORCEPROP 2 LASTPIN (-3425 3325) $PN CK13
J 0
(-3415 3335);
DISPLAY 0.617021 (-3415 3335);
PAINT ORANGE (-3415 3335);
FORCEPROP 2 LASTPIN (-3425 3275) $PN CR14
J 0
(-3415 3285);
DISPLAY 0.617021 (-3415 3285);
PAINT ORANGE (-3415 3285);
FORCEPROP 2 LASTPIN (-3425 3225) $PN CV13
J 0
(-3415 3235);
DISPLAY 0.617021 (-3415 3235);
PAINT ORANGE (-3415 3235);
FORCEPROP 2 LASTPIN (-3425 3175) $PN CW16
J 0
(-3415 3185);
DISPLAY 0.617021 (-3415 3185);
PAINT ORANGE (-3415 3185);
FORCEPROP 2 LASTPIN (-3425 3125) $PN DB15
J 0
(-3415 3135);
DISPLAY 0.617021 (-3415 3135);
PAINT ORANGE (-3415 3135);
FORCEPROP 2 LASTPIN (-3425 3075) $PN DD15
J 0
(-3415 3085);
DISPLAY 0.617021 (-3415 3085);
PAINT ORANGE (-3415 3085);
FORCEPROP 2 LASTPIN (-3425 3025) $PN DE16
J 0
(-3415 3035);
DISPLAY 0.617021 (-3415 3035);
PAINT ORANGE (-3415 3035);
FORCEPROP 2 LASTPIN (-3425 2975) $PN DF17
J 0
(-3415 2985);
DISPLAY 0.617021 (-3415 2985);
PAINT ORANGE (-3415 2985);
FORCEPROP 2 LASTPIN (-3425 2925) $PN DH17
J 0
(-3415 2935);
DISPLAY 0.617021 (-3415 2935);
PAINT ORANGE (-3415 2935);
FORCEPROP 2 LASTPIN (-3425 2875) $PN DJ18
J 0
(-3415 2885);
DISPLAY 0.617021 (-3415 2885);
PAINT ORANGE (-3415 2885);
FORCEPROP 2 LASTPIN (-3425 2825) $PN DJ20
J 0
(-3415 2835);
DISPLAY 0.617021 (-3415 2835);
PAINT ORANGE (-3415 2835);
FORCEPROP 2 LASTPIN (-3425 2775) $PN DK19
J 0
(-3415 2785);
DISPLAY 0.617021 (-3415 2785);
PAINT ORANGE (-3415 2785);
FORCEPROP 2 LASTPIN (-3425 2725) $PN DN20
J 0
(-3415 2735);
DISPLAY 0.617021 (-3415 2735);
PAINT ORANGE (-3415 2735);
FORCEPROP 2 LASTPIN (-3425 2675) $PN DP21
J 0
(-3415 2685);
DISPLAY 0.617021 (-3415 2685);
PAINT ORANGE (-3415 2685);
FORCEPROP 2 LASTPIN (-3425 2575) $PN CC12
J 0
(-3415 2585);
DISPLAY 0.617021 (-3415 2585);
PAINT ORANGE (-3415 2585);
FORCEPROP 2 LASTPIN (-3425 2525) $PN CC10
J 0
(-3415 2535);
DISPLAY 0.617021 (-3415 2535);
PAINT ORANGE (-3415 2535);
FORCEPROP 2 LASTPIN (-3425 2475) $PN CE12
J 0
(-3415 2485);
DISPLAY 0.617021 (-3415 2485);
PAINT ORANGE (-3415 2485);
FORCEPROP 2 LASTPIN (-3425 2425) $PN CH11
J 0
(-3415 2435);
DISPLAY 0.617021 (-3415 2435);
PAINT ORANGE (-3415 2435);
FORCEPROP 2 LASTPIN (-3425 2375) $PN CF13
J 0
(-3415 2385);
DISPLAY 0.617021 (-3415 2385);
PAINT ORANGE (-3415 2385);
FORCEPROP 2 LASTPIN (-3425 2325) $PN CJ14
J 0
(-3415 2335);
DISPLAY 0.617021 (-3415 2335);
PAINT ORANGE (-3415 2335);
FORCEPROP 2 LASTPIN (-3425 2275) $PN CM13
J 0
(-3415 2285);
DISPLAY 0.617021 (-3415 2285);
PAINT ORANGE (-3415 2285);
FORCEPROP 2 LASTPIN (-3425 2225) $PN CU14
J 0
(-3415 2235);
DISPLAY 0.617021 (-3415 2235);
PAINT ORANGE (-3415 2235);
FORCEPROP 2 LASTPIN (-3425 2175) $PN CW14
J 0
(-3415 2185);
DISPLAY 0.617021 (-3415 2185);
PAINT ORANGE (-3415 2185);
FORCEPROP 2 LASTPIN (-3425 2125) $PN DA16
J 0
(-3415 2135);
DISPLAY 0.617021 (-3415 2135);
PAINT ORANGE (-3415 2135);
FORCEPROP 2 LASTPIN (-3425 2075) $PN DC16
J 0
(-3415 2085);
DISPLAY 0.617021 (-3415 2085);
PAINT ORANGE (-3415 2085);
FORCEPROP 2 LASTPIN (-3425 2025) $PN DF15
J 0
(-3415 2035);
DISPLAY 0.617021 (-3415 2035);
PAINT ORANGE (-3415 2035);
FORCEPROP 2 LASTPIN (-3425 1975) $PN DD17
J 0
(-3415 1985);
DISPLAY 0.617021 (-3415 1985);
PAINT ORANGE (-3415 1985);
FORCEPROP 2 LASTPIN (-3425 1925) $PN DG18
J 0
(-3415 1935);
DISPLAY 0.617021 (-3415 1935);
PAINT ORANGE (-3415 1935);
FORCEPROP 2 LASTPIN (-3425 1875) $PN DK17
J 0
(-3415 1885);
DISPLAY 0.617021 (-3415 1885);
PAINT ORANGE (-3415 1885);
FORCEPROP 2 LASTPIN (-3425 1825) $PN DH19
J 0
(-3415 1835);
DISPLAY 0.617021 (-3415 1835);
PAINT ORANGE (-3415 1835);
FORCEPROP 2 LASTPIN (-3425 1775) $PN DG20
J 0
(-3415 1785);
DISPLAY 0.617021 (-3415 1785);
PAINT ORANGE (-3415 1785);
FORCEPROP 2 LASTPIN (-3425 1725) $PN DL20
J 0
(-3415 1735);
DISPLAY 0.617021 (-3415 1735);
PAINT ORANGE (-3415 1735);
FORCEPROP 2 LASTPIN (-3425 1675) $PN DM21
J 0
(-3415 1685);
DISPLAY 0.617021 (-3415 1685);
PAINT ORANGE (-3415 1685);
FORCEPROP 2 LASTPIN (-3425 1625) $PN DT21
J 0
(-3415 1635);
DISPLAY 0.617021 (-3415 1635);
PAINT ORANGE (-3415 1635);
FORCEPROP 2 LASTPIN (-5025 3625) $PN CA16
J 2
(-5035 3635);
DISPLAY 0.617021 (-5035 3635);
PAINT ORANGE (-5035 3635);
FORCEPROP 2 LASTPIN (-5025 3575) $PN BY15
J 2
(-5035 3585);
DISPLAY 0.617021 (-5035 3585);
PAINT ORANGE (-5035 3585);
FORCEPROP 2 LASTPIN (-5025 3525) $PN CD17
J 2
(-5035 3535);
DISPLAY 0.617021 (-5035 3535);
PAINT ORANGE (-5035 3535);
FORCEPROP 2 LASTPIN (-5025 3475) $PN CC14
J 2
(-5035 3485);
DISPLAY 0.617021 (-5035 3485);
PAINT ORANGE (-5035 3485);
FORCEPROP 2 LASTPIN (-5025 3425) $PN CF15
J 2
(-5035 3435);
DISPLAY 0.617021 (-5035 3435);
PAINT ORANGE (-5035 3435);
FORCEPROP 2 LASTPIN (-5025 3375) $PN CG16
J 2
(-5035 3385);
DISPLAY 0.617021 (-5035 3385);
PAINT ORANGE (-5035 3385);
FORCEPROP 2 LASTPIN (-5025 3325) $PN CK17
J 2
(-5035 3335);
DISPLAY 0.617021 (-5035 3335);
PAINT ORANGE (-5035 3335);
FORCEPROP 2 LASTPIN (-5025 3275) $PN CJ16
J 2
(-5035 3285);
DISPLAY 0.617021 (-5035 3285);
PAINT ORANGE (-5035 3285);
FORCEPROP 2 LASTPIN (-5025 3225) $PN CM21
J 2
(-5035 3235);
DISPLAY 0.617021 (-5035 3235);
PAINT ORANGE (-5035 3235);
FORCEPROP 2 LASTPIN (-5025 3175) $PN CP19
J 2
(-5035 3185);
DISPLAY 0.617021 (-5035 3185);
PAINT ORANGE (-5035 3185);
FORCEPROP 2 LASTPIN (-5025 3125) $PN CN18
J 2
(-5035 3135);
DISPLAY 0.617021 (-5035 3135);
PAINT ORANGE (-5035 3135);
FORCEPROP 2 LASTPIN (-5025 3075) $PN CR20
J 2
(-5035 3085);
DISPLAY 0.617021 (-5035 3085);
PAINT ORANGE (-5035 3085);
FORCEPROP 2 LASTPIN (-5025 3025) $PN CW18
J 2
(-5035 3035);
DISPLAY 0.617021 (-5035 3035);
PAINT ORANGE (-5035 3035);
FORCEPROP 2 LASTPIN (-5025 2975) $PN CU20
J 2
(-5035 2985);
DISPLAY 0.617021 (-5035 2985);
PAINT ORANGE (-5035 2985);
FORCEPROP 2 LASTPIN (-5025 2925) $PN CY19
J 2
(-5035 2935);
DISPLAY 0.617021 (-5035 2935);
PAINT ORANGE (-5035 2935);
FORCEPROP 2 LASTPIN (-5025 2875) $PN DB19
J 2
(-5035 2885);
DISPLAY 0.617021 (-5035 2885);
PAINT ORANGE (-5035 2885);
FORCEPROP 2 LASTPIN (-5025 2825) $PN DC20
J 2
(-5035 2835);
DISPLAY 0.617021 (-5035 2835);
PAINT ORANGE (-5035 2835);
FORCEPROP 2 LASTPIN (-5025 2775) $PN DA22
J 2
(-5035 2785);
DISPLAY 0.617021 (-5035 2785);
PAINT ORANGE (-5035 2785);
FORCEPROP 2 LASTPIN (-5025 2725) $PN DD21
J 2
(-5035 2735);
DISPLAY 0.617021 (-5035 2735);
PAINT ORANGE (-5035 2735);
FORCEPROP 2 LASTPIN (-5025 2675) $PN DG22
J 2
(-5035 2685);
DISPLAY 0.617021 (-5035 2685);
PAINT ORANGE (-5035 2685);
FORCEPROP 2 LASTPIN (-5025 2575) $PN BY17
J 2
(-5035 2585);
DISPLAY 0.617021 (-5035 2585);
PAINT ORANGE (-5035 2585);
FORCEPROP 2 LASTPIN (-5025 2525) $PN CB15
J 2
(-5035 2535);
DISPLAY 0.617021 (-5035 2535);
PAINT ORANGE (-5035 2535);
FORCEPROP 2 LASTPIN (-5025 2475) $PN CF17
J 2
(-5035 2485);
DISPLAY 0.617021 (-5035 2485);
PAINT ORANGE (-5035 2485);
FORCEPROP 2 LASTPIN (-5025 2425) $PN CD15
J 2
(-5035 2435);
DISPLAY 0.617021 (-5035 2435);
PAINT ORANGE (-5035 2435);
FORCEPROP 2 LASTPIN (-5025 2375) $PN CE16
J 2
(-5035 2385);
DISPLAY 0.617021 (-5035 2385);
PAINT ORANGE (-5035 2385);
FORCEPROP 2 LASTPIN (-5025 2325) $PN CH17
J 2
(-5035 2335);
DISPLAY 0.617021 (-5035 2335);
PAINT ORANGE (-5035 2335);
FORCEPROP 2 LASTPIN (-5025 2275) $PN CJ18
J 2
(-5035 2285);
DISPLAY 0.617021 (-5035 2285);
PAINT ORANGE (-5035 2285);
FORCEPROP 2 LASTPIN (-5025 2225) $PN CL16
J 2
(-5035 2235);
DISPLAY 0.617021 (-5035 2235);
PAINT ORANGE (-5035 2235);
FORCEPROP 2 LASTPIN (-5025 2175) $PN CP21
J 2
(-5035 2185);
DISPLAY 0.617021 (-5035 2185);
PAINT ORANGE (-5035 2185);
FORCEPROP 2 LASTPIN (-5025 2125) $PN CN20
J 2
(-5035 2135);
DISPLAY 0.617021 (-5035 2135);
PAINT ORANGE (-5035 2135);
FORCEPROP 2 LASTPIN (-5025 2075) $PN CR18
J 2
(-5035 2085);
DISPLAY 0.617021 (-5035 2085);
PAINT ORANGE (-5035 2085);
FORCEPROP 2 LASTPIN (-5025 2025) $PN CT21
J 2
(-5035 2035);
DISPLAY 0.617021 (-5035 2035);
PAINT ORANGE (-5035 2035);
FORCEPROP 2 LASTPIN (-5025 1975) $PN CV19
J 2
(-5035 1985);
DISPLAY 0.617021 (-5035 1985);
PAINT ORANGE (-5035 1985);
FORCEPROP 2 LASTPIN (-5025 1925) $PN CW20
J 2
(-5035 1935);
DISPLAY 0.617021 (-5035 1935);
PAINT ORANGE (-5035 1935);
FORCEPROP 2 LASTPIN (-5025 1875) $PN DA20
J 2
(-5035 1885);
DISPLAY 0.617021 (-5035 1885);
PAINT ORANGE (-5035 1885);
FORCEPROP 2 LASTPIN (-5025 1825) $PN DD19
J 2
(-5035 1835);
DISPLAY 0.617021 (-5035 1835);
PAINT ORANGE (-5035 1835);
FORCEPROP 2 LASTPIN (-5025 1775) $PN DB21
J 2
(-5035 1785);
DISPLAY 0.617021 (-5035 1785);
PAINT ORANGE (-5035 1785);
FORCEPROP 2 LASTPIN (-5025 1725) $PN DC22
J 2
(-5035 1735);
DISPLAY 0.617021 (-5035 1735);
PAINT ORANGE (-5035 1735);
FORCEPROP 2 LASTPIN (-5025 1675) $PN DE22
J 2
(-5035 1685);
DISPLAY 0.617021 (-5035 1685);
PAINT ORANGE (-5035 1685);
FORCEPROP 2 LASTPIN (-5025 1625) $PN DF23
J 2
(-5035 1635);
DISPLAY 0.617021 (-5035 1635);
PAINT ORANGE (-5035 1635);
FORCEPROP 1 LAST PACK_TYPE BGA1
J 0
(-4975 3925);
PAINT SKYBLUE (-4975 3925);
DISPLAY INVISIBLE (-4975 3925);
FORCEPROP 2 LAST CDS_LIB chpset_lib
J 0
(-4225 2625);
PAINT ORANGE (-4225 2625);
DISPLAY INVISIBLE (-4225 2625);
FORCEPROP 2 LAST SEC_TYPE BGA1
J 0
(-4975 3925);
DISPLAY 1.021277 (-4975 3925);
PAINT ORANGE (-4975 3925);
DISPLAY INVISIBLE (-4975 3925);
FORCEPROP 2 LAST SEC 15
J 0
(-4975 3925);
DISPLAY 0.680851 (-4975 3925);
PAINT MONO (-4975 3925);
DISPLAY INVISIBLE (-4975 3925);
FORCEPROP 2 LAST CDS_LOCATION U5D1
J 0
(-4975 3875);
DISPLAY 0.617021 (-4975 3875);
PAINT AQUA (-4975 3875);
DISPLAY INVISIBLE (-4975 3875);
FORCEPROP 1 LAST PATH I3
J 0
(-4225 3825);
PAINT GREEN (-4225 3825);
DISPLAY INVISIBLE (-4225 3825);
FORCEPROP 0 LAST ROOM CPU0
J 0
(-4975 3975);
DISPLAY 1.021277 (-4975 3975);
PAINT ORANGE (-4975 3975);
DISPLAY INVISIBLE (-4975 3975);
FORCEADD DESIGN_NOTE..1
(-4850 1325);
FORCEPROP 0 LAST L1 CPU SYMBOLS 1-30 ARE PRELIMINARY AND SUBJECT TO CHANGE
J 0
(-5050 1200);
DISPLAY 1.021277 (-5050 1200);
PAINT ORANGE (-5050 1200);
FORCEPROP 2 LAST CDS_LIB mstr_symbols
J 0
(-4850 1325);
PAINT ORANGE (-4850 1325);
DISPLAY INVISIBLE (-4850 1325);
FORCEPROP 1 LAST COMMENT_BODY TRUE
J 0
(-4825 1425);
DISPLAY 0.978723 (-4825 1425);
PAINT ORANGE (-4825 1425);
DISPLAY INVISIBLE (-4825 1425);
FORCEADD INTEL_CORP_BPAGE..1
(0 0);
FORCEPROP 1 LAST CDS_CON_LAST_MODIFIED Tue Dec 01 11:51:22 2015
J 0
(-1425 325);
DISPLAY 1.340426 (-1425 325);
PAINT GREEN (-1425 325);
DISPLAY INVISIBLE (-1425 325);
FORCEPROP 1 LAST CUSTOM_TXT_CDS <CURRENT_DESIGN_SHEET> OF <TOTAL_DESIGN_SHEETS>
J 0
(-500 25);
PAINT GREEN (-500 25);
FORCEPROP 1 LAST CUSTOM_TXT_CDS <CON_LAST_MODIFIED>
J 0
(-1925 350);
PAINT GREEN (-1925 350);
FORCEPROP 2 LAST CUSTOM_TXT_CDS <XR_PAGE_TITLE>
J 0
(-7890 5250);
DISPLAY 0.638298 (-7890 5250);
PAINT PINK (-7890 5250);
DISPLAY INVISIBLE (-7890 5250);
FORCEPROP 1 LAST SCH_ADDRESS3 Santa Clara, CA 95052-8119
J 0
(-3975 25);
DISPLAY 0.617021 (-3975 25);
PAINT GREEN (-3975 25);
FORCEPROP 1 LAST SCH_ADDRESS2 P.O. BOX 58119
J 0
(-3975 75);
DISPLAY 0.617021 (-3975 75);
PAINT GREEN (-3975 75);
FORCEPROP 1 LAST SCH_ADDRESS1 2200 Mission College Blvd.
J 0
(-3975 125);
DISPLAY 0.617021 (-3975 125);
PAINT GREEN (-3975 125);
FORCEPROP 1 LAST SCH_TITLE SKYLAKE - SKT0 - 15 OF 21
J 0
(-7950 50);
DISPLAY 1.212766 (-7950 50);
PAINT GREEN (-7950 50);
FORCEPROP 1 LAST SCH_NUMBER H4694802
J 0
(-1300 150);
DISPLAY 1.212766 (-1300 150);
PAINT YELLOW (-1300 150);
FORCEPROP 1 LAST SCH_DEPT BESD
J 1
(-4450 100);
DISPLAY 1.212766 (-4450 100);
PAINT YELLOW (-4450 100);
FORCEPROP 1 LAST SCH_REV 2.420
J 0
(-250 150);
DISPLAY 0.978723 (-250 150);
PAINT YELLOW (-250 150);
FORCEPROP 2 LAST CDS_LIB mstr_symbols
J 0
(0 0);
PAINT ORANGE (0 0);
DISPLAY INVISIBLE (0 0);
FORCEPROP 2 LAST PAGE_BORDER TRUE
J 0
(-7890 5250);
DISPLAY 0.851064 (-7890 5250);
PAINT PINK (-7890 5250);
DISPLAY INVISIBLE (-7890 5250);
FORCEPROP 1 LAST COMMENT_BODY TRUE
J 0
(12 12);
DISPLAY 0.638298 (12 12);
PAINT GREEN (12 12);
DISPLAY INVISIBLE (12 12);
FORCEPROP 2 LAST CDS_XR_PAGE_TITLE CR-35 : @BASEBOARD_FAB2_LIB.BASEBOARD_FAB2(SCH_1):PAGE35
J 0
(-7890 5250);
DISPLAY 0.638298 (-7890 5250);
PAINT PINK (-7890 5250);
DISPLAY INVISIBLE (-7890 5250);
WIRE 16 -1 (-5025 3625)(-5975 3625);
WIRE 16 -1 (-5975 3625)(-5975 3575);
WIRE 16 -1 (-5025 3575)(-5975 3575);
WIRE 16 -1 (-5975 3575)(-5975 3525);
WIRE 16 -1 (-5025 3525)(-5975 3525);
WIRE 16 -1 (-5975 3525)(-5975 3475);
WIRE 16 -1 (-5025 3475)(-5975 3475);
WIRE 16 -1 (-5975 3475)(-5975 3425);
WIRE 16 -1 (-5025 3425)(-5975 3425);
WIRE 16 -1 (-5975 3425)(-5975 3375);
WIRE 16 -1 (-5025 3375)(-5975 3375);
WIRE 16 -1 (-5975 3375)(-5975 3325);
WIRE 16 -1 (-5025 3325)(-5975 3325);
WIRE 16 -1 (-5975 3325)(-5975 3275);
WIRE 16 -1 (-5025 3275)(-5975 3275);
WIRE 16 -1 (-5975 3275)(-5975 3225);
WIRE 16 -1 (-5025 3225)(-5975 3225);
WIRE 16 -1 (-5975 3225)(-5975 3175);
WIRE 16 -1 (-5025 3175)(-5975 3175);
WIRE 16 -1 (-5975 3175)(-5975 3125);
WIRE 16 -1 (-5025 3125)(-5975 3125);
WIRE 16 -1 (-5975 3125)(-5975 3075);
WIRE 16 -1 (-5025 3075)(-5975 3075);
WIRE 16 -1 (-5975 3075)(-5975 3025);
WIRE 16 -1 (-5025 3025)(-5975 3025);
WIRE 16 -1 (-5975 3025)(-5975 2975);
WIRE 16 -1 (-5025 2975)(-5975 2975);
WIRE 16 -1 (-5975 2975)(-5975 2925);
WIRE 16 -1 (-5025 2925)(-5975 2925);
WIRE 16 -1 (-5975 2925)(-5975 2875);
WIRE 16 -1 (-5025 2875)(-5975 2875);
WIRE 16 -1 (-5975 2875)(-5975 2825);
WIRE 16 -1 (-5025 2825)(-5975 2825);
WIRE 16 -1 (-5975 2825)(-5975 2775);
WIRE 16 -1 (-5025 2775)(-5975 2775);
WIRE 16 -1 (-5975 2775)(-5975 2725);
WIRE 16 -1 (-5025 2725)(-5975 2725);
WIRE 16 -1 (-5975 2725)(-5975 2675);
WIRE 16 -1 (-5025 2675)(-5975 2675);
WIRE 16 -1 (-5975 2675)(-5975 2575);
WIRE 16 -1 (-5025 2575)(-5975 2575);
WIRE 16 -1 (-5975 2575)(-5975 2525);
WIRE 16 -1 (-5025 2525)(-5975 2525);
WIRE 16 -1 (-5975 2525)(-5975 2475);
WIRE 16 -1 (-5025 2475)(-5975 2475);
WIRE 16 -1 (-5975 2475)(-5975 2425);
WIRE 16 -1 (-5025 2425)(-5975 2425);
WIRE 16 -1 (-5975 2425)(-5975 2375);
WIRE 16 -1 (-5025 2375)(-5975 2375);
WIRE 16 -1 (-5975 2375)(-5975 2325);
WIRE 16 -1 (-5025 2325)(-5975 2325);
WIRE 16 -1 (-5975 2325)(-5975 2275);
WIRE 16 -1 (-5025 2275)(-5975 2275);
WIRE 16 -1 (-5975 2275)(-5975 2225);
WIRE 16 -1 (-5025 2225)(-5975 2225);
WIRE 16 -1 (-5975 2225)(-5975 2175);
WIRE 16 -1 (-5025 2175)(-5975 2175);
WIRE 16 -1 (-5975 2175)(-5975 2125);
WIRE 16 -1 (-5025 2125)(-5975 2125);
WIRE 16 -1 (-5975 2125)(-5975 2075);
WIRE 16 -1 (-5025 2075)(-5975 2075);
WIRE 16 -1 (-5975 2075)(-5975 2025);
WIRE 16 -1 (-5025 2025)(-5975 2025);
WIRE 16 -1 (-5975 2025)(-5975 1975);
WIRE 16 -1 (-5025 1975)(-5975 1975);
WIRE 16 -1 (-5975 1975)(-5975 1925);
WIRE 16 -1 (-5025 1925)(-5975 1925);
WIRE 16 -1 (-5975 1925)(-5975 1875);
WIRE 16 -1 (-5025 1875)(-5975 1875);
WIRE 16 -1 (-5975 1875)(-5975 1825);
WIRE 16 -1 (-5025 1825)(-5975 1825);
WIRE 16 -1 (-5975 1825)(-5975 1775);
WIRE 16 -1 (-5025 1775)(-5975 1775);
WIRE 16 -1 (-5975 1775)(-5975 1725);
WIRE 16 -1 (-5025 1725)(-5975 1725);
WIRE 16 -1 (-5975 1725)(-5975 1675);
WIRE 16 -1 (-5025 1675)(-5975 1675);
WIRE 16 -1 (-5975 1675)(-5975 1625);
WIRE 16 -1 (-5025 1625)(-5975 1625);
WIRE 16 -1 (-5975 1625)(-5975 1450);
WIRE 16 -1 (-2475 1625)(-3425 1625);
FORCEPROP 0 LAST SIG_NAME TP_CPU0_UPI2_RSVD_CC12
J 0
(-3075 1635);
DISPLAY 0.617021 (-3075 1635);
PAINT ORANGE (-3075 1635);
FORCEPROP 2 LASTPROP $XRERR UNIQUE?
J 0
(-2445 1625);
DISPLAY 0.638298 (-2445 1625);
PAINT MONO (-2445 1625);
DISPLAY INVISIBLE (-2445 1625);
WIRE 16 -1 (-2475 1675)(-3425 1675);
FORCEPROP 0 LAST SIG_NAME TP_CPU0_UPI2_RSVD_CC10
J 0
(-3075 1685);
DISPLAY 0.617021 (-3075 1685);
PAINT ORANGE (-3075 1685);
FORCEPROP 2 LASTPROP $XRERR UNIQUE?
J 0
(-2445 1675);
DISPLAY 0.638298 (-2445 1675);
PAINT MONO (-2445 1675);
DISPLAY INVISIBLE (-2445 1675);
WIRE 16 -1 (-2475 1725)(-3425 1725);
FORCEPROP 0 LAST SIG_NAME TP_CPU0_UPI2_RSVD_CE12
J 0
(-3075 1735);
DISPLAY 0.617021 (-3075 1735);
PAINT ORANGE (-3075 1735);
FORCEPROP 2 LASTPROP $XRERR UNIQUE?
J 0
(-2445 1725);
DISPLAY 0.638298 (-2445 1725);
PAINT MONO (-2445 1725);
DISPLAY INVISIBLE (-2445 1725);
WIRE 16 -1 (-2475 1775)(-3425 1775);
FORCEPROP 0 LAST SIG_NAME TP_CPU0_UPI2_RSVD_CH11
J 0
(-3075 1785);
DISPLAY 0.617021 (-3075 1785);
PAINT ORANGE (-3075 1785);
FORCEPROP 2 LASTPROP $XRERR UNIQUE?
J 0
(-2445 1775);
DISPLAY 0.638298 (-2445 1775);
PAINT MONO (-2445 1775);
DISPLAY INVISIBLE (-2445 1775);
WIRE 16 -1 (-2475 1825)(-3425 1825);
FORCEPROP 0 LAST SIG_NAME TP_CPU0_UPI2_RSVD_CF13
J 0
(-3075 1835);
DISPLAY 0.617021 (-3075 1835);
PAINT ORANGE (-3075 1835);
FORCEPROP 2 LASTPROP $XRERR UNIQUE?
J 0
(-2445 1825);
DISPLAY 0.638298 (-2445 1825);
PAINT MONO (-2445 1825);
DISPLAY INVISIBLE (-2445 1825);
WIRE 16 -1 (-2475 1875)(-3425 1875);
FORCEPROP 0 LAST SIG_NAME TP_CPU0_UPI2_RSVD_CJ14
J 0
(-3075 1885);
DISPLAY 0.617021 (-3075 1885);
PAINT ORANGE (-3075 1885);
FORCEPROP 2 LASTPROP $XRERR UNIQUE?
J 0
(-2445 1875);
DISPLAY 0.638298 (-2445 1875);
PAINT MONO (-2445 1875);
DISPLAY INVISIBLE (-2445 1875);
WIRE 16 -1 (-2475 1925)(-3425 1925);
FORCEPROP 0 LAST SIG_NAME TP_CPU0_UPI2_RSVD_CM13
J 0
(-3075 1935);
DISPLAY 0.617021 (-3075 1935);
PAINT ORANGE (-3075 1935);
FORCEPROP 2 LASTPROP $XRERR UNIQUE?
J 0
(-2445 1925);
DISPLAY 0.638298 (-2445 1925);
PAINT MONO (-2445 1925);
DISPLAY INVISIBLE (-2445 1925);
WIRE 16 -1 (-2475 1975)(-3425 1975);
FORCEPROP 0 LAST SIG_NAME TP_CPU0_UPI2_RSVD_CU14
J 0
(-3075 1985);
DISPLAY 0.617021 (-3075 1985);
PAINT ORANGE (-3075 1985);
FORCEPROP 2 LASTPROP $XRERR UNIQUE?
J 0
(-2445 1975);
DISPLAY 0.638298 (-2445 1975);
PAINT MONO (-2445 1975);
DISPLAY INVISIBLE (-2445 1975);
WIRE 16 -1 (-2475 2025)(-3425 2025);
FORCEPROP 0 LAST SIG_NAME TP_CPU0_UPI2_RSVD_CW14
J 0
(-3075 2035);
DISPLAY 0.617021 (-3075 2035);
PAINT ORANGE (-3075 2035);
FORCEPROP 2 LASTPROP $XRERR UNIQUE?
J 0
(-2445 2025);
DISPLAY 0.638298 (-2445 2025);
PAINT MONO (-2445 2025);
DISPLAY INVISIBLE (-2445 2025);
WIRE 16 -1 (-2475 2675)(-3425 2675);
FORCEPROP 0 LAST SIG_NAME TP_CPU0_UPI2_RSVD_CA12
J 0
(-3075 2685);
DISPLAY 0.617021 (-3075 2685);
PAINT ORANGE (-3075 2685);
FORCEPROP 2 LASTPROP $XRERR UNIQUE?
J 0
(-2445 2675);
DISPLAY 0.638298 (-2445 2675);
PAINT MONO (-2445 2675);
DISPLAY INVISIBLE (-2445 2675);
WIRE 16 -1 (-2475 2725)(-3425 2725);
FORCEPROP 0 LAST SIG_NAME TP_CPU0_UPI2_RSVD_CB11
J 0
(-3075 2735);
DISPLAY 0.617021 (-3075 2735);
PAINT ORANGE (-3075 2735);
FORCEPROP 2 LASTPROP $XRERR UNIQUE?
J 0
(-2445 2725);
DISPLAY 0.638298 (-2445 2725);
PAINT MONO (-2445 2725);
DISPLAY INVISIBLE (-2445 2725);
WIRE 16 -1 (-2475 2775)(-3425 2775);
FORCEPROP 0 LAST SIG_NAME TP_CPU0_UPI2_RSVD_CD11
J 0
(-3075 2785);
DISPLAY 0.617021 (-3075 2785);
PAINT ORANGE (-3075 2785);
FORCEPROP 2 LASTPROP $XRERR UNIQUE?
J 0
(-2445 2775);
DISPLAY 0.638298 (-2445 2775);
PAINT MONO (-2445 2775);
DISPLAY INVISIBLE (-2445 2775);
WIRE 16 -1 (-2475 2825)(-3425 2825);
FORCEPROP 0 LAST SIG_NAME TP_CPU0_UPI2_RSVD_CF11
J 0
(-3075 2835);
DISPLAY 0.617021 (-3075 2835);
PAINT ORANGE (-3075 2835);
FORCEPROP 2 LASTPROP $XRERR UNIQUE?
J 0
(-2445 2825);
DISPLAY 0.638298 (-2445 2825);
PAINT MONO (-2445 2825);
DISPLAY INVISIBLE (-2445 2825);
WIRE 16 -1 (-2475 2875)(-3425 2875);
FORCEPROP 0 LAST SIG_NAME TP_CPU0_UPI2_RSVD_CG12
J 0
(-3075 2885);
DISPLAY 0.617021 (-3075 2885);
PAINT ORANGE (-3075 2885);
FORCEPROP 2 LASTPROP $XRERR UNIQUE?
J 0
(-2445 2875);
DISPLAY 0.638298 (-2445 2875);
PAINT MONO (-2445 2875);
DISPLAY INVISIBLE (-2445 2875);
WIRE 16 -1 (-2475 2925)(-3425 2925);
FORCEPROP 0 LAST SIG_NAME TP_CPU0_UPI2_RSVD_CH13
J 0
(-3075 2935);
DISPLAY 0.617021 (-3075 2935);
PAINT ORANGE (-3075 2935);
FORCEPROP 2 LASTPROP $XRERR UNIQUE?
J 0
(-2445 2925);
DISPLAY 0.638298 (-2445 2925);
PAINT MONO (-2445 2925);
DISPLAY INVISIBLE (-2445 2925);
WIRE 16 -1 (-2475 2975)(-3425 2975);
FORCEPROP 0 LAST SIG_NAME TP_CPU0_UPI2_RSVD_CK13
J 0
(-3075 2985);
DISPLAY 0.617021 (-3075 2985);
PAINT ORANGE (-3075 2985);
FORCEPROP 2 LASTPROP $XRERR UNIQUE?
J 0
(-2445 2975);
DISPLAY 0.638298 (-2445 2975);
PAINT MONO (-2445 2975);
DISPLAY INVISIBLE (-2445 2975);
WIRE 16 -1 (-2475 3025)(-3425 3025);
FORCEPROP 0 LAST SIG_NAME TP_CPU0_UPI2_RSVD_CR14
J 0
(-3075 3035);
DISPLAY 0.617021 (-3075 3035);
PAINT ORANGE (-3075 3035);
FORCEPROP 2 LASTPROP $XRERR UNIQUE?
J 0
(-2445 3025);
DISPLAY 0.638298 (-2445 3025);
PAINT MONO (-2445 3025);
DISPLAY INVISIBLE (-2445 3025);
WIRE 16 -1 (-2475 3075)(-3425 3075);
FORCEPROP 0 LAST SIG_NAME TP_CPU0_UPI2_RSVD_CV13
J 0
(-3075 3085);
DISPLAY 0.617021 (-3075 3085);
PAINT ORANGE (-3075 3085);
FORCEPROP 2 LASTPROP $XRERR UNIQUE?
J 0
(-2445 3075);
DISPLAY 0.638298 (-2445 3075);
PAINT MONO (-2445 3075);
DISPLAY INVISIBLE (-2445 3075);
WIRE 16 -1 (-2475 3125)(-3425 3125);
FORCEPROP 0 LAST SIG_NAME TP_CPU0_UPI2_RSVD_CW16
J 0
(-3075 3135);
DISPLAY 0.617021 (-3075 3135);
PAINT ORANGE (-3075 3135);
FORCEPROP 2 LASTPROP $XRERR UNIQUE?
J 0
(-2445 3125);
DISPLAY 0.638298 (-2445 3125);
PAINT MONO (-2445 3125);
DISPLAY INVISIBLE (-2445 3125);
WIRE 16 -1 (-2475 3175)(-3425 3175);
FORCEPROP 0 LAST SIG_NAME TP_CPU0_UPI2_RSVD_DB15
J 0
(-3075 3185);
DISPLAY 0.617021 (-3075 3185);
PAINT ORANGE (-3075 3185);
FORCEPROP 2 LASTPROP $XRERR UNIQUE?
J 0
(-2445 3175);
DISPLAY 0.638298 (-2445 3175);
PAINT MONO (-2445 3175);
DISPLAY INVISIBLE (-2445 3175);
WIRE 16 -1 (-2475 3225)(-3425 3225);
FORCEPROP 0 LAST SIG_NAME TP_CPU0_UPI2_RSVD_DD15
J 0
(-3075 3235);
DISPLAY 0.617021 (-3075 3235);
PAINT ORANGE (-3075 3235);
FORCEPROP 2 LASTPROP $XRERR UNIQUE?
J 0
(-2445 3225);
DISPLAY 0.638298 (-2445 3225);
PAINT MONO (-2445 3225);
DISPLAY INVISIBLE (-2445 3225);
WIRE 16 -1 (-2475 3275)(-3425 3275);
FORCEPROP 0 LAST SIG_NAME TP_CPU0_UPI2_RSVD_DE16
J 0
(-3075 3285);
DISPLAY 0.617021 (-3075 3285);
PAINT ORANGE (-3075 3285);
FORCEPROP 2 LASTPROP $XRERR UNIQUE?
J 0
(-2445 3275);
DISPLAY 0.638298 (-2445 3275);
PAINT MONO (-2445 3275);
DISPLAY INVISIBLE (-2445 3275);
WIRE 16 -1 (-2475 3325)(-3425 3325);
FORCEPROP 0 LAST SIG_NAME TP_CPU0_UPI2_RSVD_DF17
J 0
(-3075 3335);
DISPLAY 0.617021 (-3075 3335);
PAINT ORANGE (-3075 3335);
FORCEPROP 2 LASTPROP $XRERR UNIQUE?
J 0
(-2445 3325);
DISPLAY 0.638298 (-2445 3325);
PAINT MONO (-2445 3325);
DISPLAY INVISIBLE (-2445 3325);
WIRE 16 -1 (-2475 3375)(-3425 3375);
FORCEPROP 0 LAST SIG_NAME TP_CPU0_UPI2_RSVD_DH17
J 0
(-3075 3385);
DISPLAY 0.617021 (-3075 3385);
PAINT ORANGE (-3075 3385);
FORCEPROP 2 LASTPROP $XRERR UNIQUE?
J 0
(-2445 3375);
DISPLAY 0.638298 (-2445 3375);
PAINT MONO (-2445 3375);
DISPLAY INVISIBLE (-2445 3375);
WIRE 16 -1 (-2475 3425)(-3425 3425);
FORCEPROP 0 LAST SIG_NAME TP_CPU0_UPI2_RSVD_DJ18
J 0
(-3075 3435);
DISPLAY 0.617021 (-3075 3435);
PAINT ORANGE (-3075 3435);
FORCEPROP 2 LASTPROP $XRERR UNIQUE?
J 0
(-2445 3425);
DISPLAY 0.638298 (-2445 3425);
PAINT MONO (-2445 3425);
DISPLAY INVISIBLE (-2445 3425);
WIRE 16 -1 (-2475 3475)(-3425 3475);
FORCEPROP 0 LAST SIG_NAME TP_CPU0_UPI2_RSVD_DJ20
J 0
(-3075 3485);
DISPLAY 0.617021 (-3075 3485);
PAINT ORANGE (-3075 3485);
FORCEPROP 2 LASTPROP $XRERR UNIQUE?
J 0
(-2445 3475);
DISPLAY 0.638298 (-2445 3475);
PAINT MONO (-2445 3475);
DISPLAY INVISIBLE (-2445 3475);
WIRE 16 -1 (-2475 3525)(-3425 3525);
FORCEPROP 0 LAST SIG_NAME TP_CPU0_UPI2_RSVD_DK19
J 0
(-3075 3535);
DISPLAY 0.617021 (-3075 3535);
PAINT ORANGE (-3075 3535);
FORCEPROP 2 LASTPROP $XRERR UNIQUE?
J 0
(-2445 3525);
DISPLAY 0.638298 (-2445 3525);
PAINT MONO (-2445 3525);
DISPLAY INVISIBLE (-2445 3525);
WIRE 16 -1 (-2475 3575)(-3425 3575);
FORCEPROP 0 LAST SIG_NAME TP_CPU0_UPI2_RSVD_DN20
J 0
(-3075 3585);
DISPLAY 0.617021 (-3075 3585);
PAINT ORANGE (-3075 3585);
FORCEPROP 2 LASTPROP $XRERR UNIQUE?
J 0
(-2445 3575);
DISPLAY 0.638298 (-2445 3575);
PAINT MONO (-2445 3575);
DISPLAY INVISIBLE (-2445 3575);
WIRE 16 -1 (-2475 3625)(-3425 3625);
FORCEPROP 0 LAST SIG_NAME TP_CPU0_UPI2_RSVD_DP21
J 0
(-3075 3635);
DISPLAY 0.617021 (-3075 3635);
PAINT ORANGE (-3075 3635);
FORCEPROP 2 LASTPROP $XRERR UNIQUE?
J 0
(-2445 3625);
DISPLAY 0.638298 (-2445 3625);
PAINT MONO (-2445 3625);
DISPLAY INVISIBLE (-2445 3625);
WIRE 16 -1 (-2475 2075)(-3425 2075);
FORCEPROP 0 LAST SIG_NAME TP_CPU0_UPI2_RSVD_DA16
J 0
(-3075 2085);
DISPLAY 0.617021 (-3075 2085);
PAINT ORANGE (-3075 2085);
FORCEPROP 2 LASTPROP $XRERR UNIQUE?
J 0
(-2445 2075);
DISPLAY 0.638298 (-2445 2075);
PAINT MONO (-2445 2075);
DISPLAY INVISIBLE (-2445 2075);
WIRE 16 -1 (-2475 2125)(-3425 2125);
FORCEPROP 0 LAST SIG_NAME TP_CPU0_UPI2_RSVD_DC16
J 0
(-3075 2135);
DISPLAY 0.617021 (-3075 2135);
PAINT ORANGE (-3075 2135);
FORCEPROP 2 LASTPROP $XRERR UNIQUE?
J 0
(-2445 2125);
DISPLAY 0.638298 (-2445 2125);
PAINT MONO (-2445 2125);
DISPLAY INVISIBLE (-2445 2125);
WIRE 16 -1 (-2475 2175)(-3425 2175);
FORCEPROP 0 LAST SIG_NAME TP_CPU0_UPI2_RSVD_DF15
J 0
(-3075 2185);
DISPLAY 0.617021 (-3075 2185);
PAINT ORANGE (-3075 2185);
FORCEPROP 2 LASTPROP $XRERR UNIQUE?
J 0
(-2445 2175);
DISPLAY 0.638298 (-2445 2175);
PAINT MONO (-2445 2175);
DISPLAY INVISIBLE (-2445 2175);
WIRE 16 -1 (-2475 2225)(-3425 2225);
FORCEPROP 0 LAST SIG_NAME TP_CPU0_UPI2_RSVD_DD17
J 0
(-3075 2235);
DISPLAY 0.617021 (-3075 2235);
PAINT ORANGE (-3075 2235);
FORCEPROP 2 LASTPROP $XRERR UNIQUE?
J 0
(-2445 2225);
DISPLAY 0.638298 (-2445 2225);
PAINT MONO (-2445 2225);
DISPLAY INVISIBLE (-2445 2225);
WIRE 16 -1 (-2475 2275)(-3425 2275);
FORCEPROP 0 LAST SIG_NAME TP_CPU0_UPI2_RSVD_DG18
J 0
(-3075 2285);
DISPLAY 0.617021 (-3075 2285);
PAINT ORANGE (-3075 2285);
FORCEPROP 2 LASTPROP $XRERR UNIQUE?
J 0
(-2445 2275);
DISPLAY 0.638298 (-2445 2275);
PAINT MONO (-2445 2275);
DISPLAY INVISIBLE (-2445 2275);
WIRE 16 -1 (-2475 2325)(-3425 2325);
FORCEPROP 0 LAST SIG_NAME TP_CPU0_UPI2_RSVD_DK17
J 0
(-3075 2335);
DISPLAY 0.617021 (-3075 2335);
PAINT ORANGE (-3075 2335);
FORCEPROP 2 LASTPROP $XRERR UNIQUE?
J 0
(-2445 2325);
DISPLAY 0.638298 (-2445 2325);
PAINT MONO (-2445 2325);
DISPLAY INVISIBLE (-2445 2325);
WIRE 16 -1 (-2475 2375)(-3425 2375);
FORCEPROP 0 LAST SIG_NAME TP_CPU0_UPI2_RSVD_DH19
J 0
(-3075 2385);
DISPLAY 0.617021 (-3075 2385);
PAINT ORANGE (-3075 2385);
FORCEPROP 2 LASTPROP $XRERR UNIQUE?
J 0
(-2445 2375);
DISPLAY 0.638298 (-2445 2375);
PAINT MONO (-2445 2375);
DISPLAY INVISIBLE (-2445 2375);
WIRE 16 -1 (-2475 2425)(-3425 2425);
FORCEPROP 0 LAST SIG_NAME TP_CPU0_UPI2_RSVD_DG20
J 0
(-3075 2435);
DISPLAY 0.617021 (-3075 2435);
PAINT ORANGE (-3075 2435);
FORCEPROP 2 LASTPROP $XRERR UNIQUE?
J 0
(-2445 2425);
DISPLAY 0.638298 (-2445 2425);
PAINT MONO (-2445 2425);
DISPLAY INVISIBLE (-2445 2425);
WIRE 16 -1 (-2475 2475)(-3425 2475);
FORCEPROP 0 LAST SIG_NAME TP_CPU0_UPI2_RSVD_DL20
J 0
(-3075 2485);
DISPLAY 0.617021 (-3075 2485);
PAINT ORANGE (-3075 2485);
FORCEPROP 2 LASTPROP $XRERR UNIQUE?
J 0
(-2445 2475);
DISPLAY 0.638298 (-2445 2475);
PAINT MONO (-2445 2475);
DISPLAY INVISIBLE (-2445 2475);
WIRE 16 -1 (-2475 2525)(-3425 2525);
FORCEPROP 0 LAST SIG_NAME TP_CPU0_UPI2_RSVD_DM21
J 0
(-3075 2535);
DISPLAY 0.617021 (-3075 2535);
PAINT ORANGE (-3075 2535);
FORCEPROP 2 LASTPROP $XRERR UNIQUE?
J 0
(-2445 2525);
DISPLAY 0.638298 (-2445 2525);
PAINT MONO (-2445 2525);
DISPLAY INVISIBLE (-2445 2525);
WIRE 16 -1 (-2475 2575)(-3425 2575);
FORCEPROP 0 LAST SIG_NAME TP_CPU0_UPI2_RSVD_DT21
J 0
(-3075 2585);
DISPLAY 0.617021 (-3075 2585);
PAINT ORANGE (-3075 2585);
FORCEPROP 2 LASTPROP $XRERR UNIQUE?
J 0
(-2445 2575);
DISPLAY 0.638298 (-2445 2575);
PAINT MONO (-2445 2575);
DISPLAY INVISIBLE (-2445 2575);
DOT 1 (-5975 3575);
DOT 1 (-5975 3525);
DOT 1 (-5975 3475);
DOT 1 (-5975 3425);
DOT 1 (-5975 3375);
DOT 1 (-5975 3325);
DOT 1 (-5975 3275);
DOT 1 (-5975 3225);
DOT 1 (-5975 3175);
DOT 1 (-5975 3125);
DOT 1 (-5975 3075);
DOT 1 (-5975 3025);
DOT 1 (-5975 2975);
DOT 1 (-5975 2925);
DOT 1 (-5975 2875);
DOT 1 (-5975 2825);
DOT 1 (-5975 2775);
DOT 1 (-5975 2725);
DOT 1 (-5975 2675);
DOT 1 (-5975 2575);
DOT 1 (-5975 2525);
DOT 1 (-5975 2475);
DOT 1 (-5975 2425);
DOT 1 (-5975 2375);
DOT 1 (-5975 2325);
DOT 1 (-5975 2275);
DOT 1 (-5975 2225);
DOT 1 (-5975 2175);
DOT 1 (-5975 2125);
DOT 1 (-5975 2075);
DOT 1 (-5975 2025);
DOT 1 (-5975 1975);
DOT 1 (-5975 1925);
DOT 1 (-5975 1875);
DOT 1 (-5975 1825);
DOT 1 (-5975 1775);
DOT 1 (-5975 1725);
DOT 1 (-5975 1675);
DOT 1 (-5975 1625);
FORCENOTE
BOM_COST=PROC_SOCKET
(-7925 250) 0;
DISPLAY LEFT (-7925 250);
DISPLAY 1.723404 (-7925 250);
PAINT PURPLE (-7925 250);
FORCENOTE
ROOM=CPU0
(-7925 375) 0;
DISPLAY LEFT (-7925 375);
DISPLAY 1.723404 (-7925 375);
PAINT PURPLE (-7925 375);
QUIT
